# S9S_MB_2U (Grand Teton) — schematic netlist excerpt (pin names and nets, part order shuffled) for the footprints in the layout excerpt that follows; sources: Cadence DE-HDL packaged netlist, KiCad conversion of 03242023_DA0F0TMBIJ0_F0T_Motherboard_J_brd_V01_OCP.brd

SW5  SW_PUSHBUTTON4P_24  SW4S_DTSM-61N-S-Q-T/R MECH  pkg SW4S_DTSM-61N  page 201
  \1\  = PD_RST_RTCRST_N
  \2\  = PD_RST_RTCRST_N
  \3\  = RST_RTCRST_N
  \4\  = RST_RTCRST_N

C2179  Q_CAP  100NF 50V 10% X7R  pkg C0402  page 301 : A = HSC_EN ; B = AGND_HSC

(kicad_pcb
	(version 20260206)
	(generator "pcbnew")
	(generator_version "10.0")
	(general
		(thickness 1.6)
		(legacy_teardrops no)
	)
	(paper "A4")
	(title_block
		(title "03242023_DA0F0TMBIJ0_F0T_Motherboard_J_brd_V01_OCP.brd")
		(comment 1 "Grand Teton / footprints 2282-2283 of 6105")
	)
	(layers
		(0 "F.Cu" signal "TOP")
		(4 "In1.Cu" signal "GND")
		(6 "In2.Cu" signal "IN1")
		(8 "In3.Cu" signal "GND1")
		(10 "In4.Cu" signal "IN2")
		(12 "In5.Cu" signal "GND2")
		(14 "In6.Cu" signal "IN3")
		(16 "In7.Cu" signal "GND3")
		(18 "In8.Cu" signal "VCC")
		(20 "In9.Cu" signal "VCC1")
		(22 "In10.Cu" signal "GND4")
		(24 "In11.Cu" signal "IN4")
		(26 "In12.Cu" signal "GND5")
		(28 "In13.Cu" signal "IN5")
		(30 "In14.Cu" signal "GND6")
		(32 "In15.Cu" signal "IN6")
		(34 "In16.Cu" signal "GND7")
		(2 "B.Cu" signal "BOTTOM")
		(9 "F.Adhes" user "F.Adhesive")
		(11 "B.Adhes" user "B.Adhesive")
		(13 "F.Paste" user "Package Geometry/Pastemask Top")
		(15 "B.Paste" user "Package Geometry/Pastemask Bottom")
		(5 "F.SilkS" user "Ref Des/Silkscreen Top")
		(7 "B.SilkS" user "Ref Des/Silkscreen Bottom")
		(1 "F.Mask" user "Board Geometry/Soldermask Top")
		(3 "B.Mask" user "Board Geometry/Soldermask Bottom")
		(17 "Dwgs.User" user "User.Drawings")
		(19 "Cmts.User" user "User.Comments")
		(21 "Eco1.User" user "User.Eco1")
		(23 "Eco2.User" user "User.Eco2")
		(25 "Edge.Cuts" user "Board Geometry/Outline")
		(27 "Margin" user)
		(31 "F.CrtYd" user "Package Geometry/Place Bound Top")
		(29 "B.CrtYd" user "Package Geometry/Place Bound Bottom")
		(35 "F.Fab" user "Ref Des/Assembly Top")
		(33 "B.Fab" user "Ref Des/Assembly Bottom")
	)
	(footprint ""
		(layer "F.Cu")
		(at 183.37403 -397.278352 180)
		(property "Reference" "C2179"
			(at 0 0 180)
			(layer "F.SilkS")
			(hide yes)
			(effects
				(font
					(size 1.27 1.27)
				)
			)
		)
		(property "Value" ""
			(at 0 0 180)
			(layer "F.Fab")
			(effects
				(font
					(size 1.27 1.27)
				)
			)
		)
		(duplicate_pad_numbers_are_jumpers no)
		(fp_line
			(start 0.7874 0.4064)
			(end -0.7874 0.4064)
			(stroke
				(width 0.1524)
				(type default)
			)
			(layer "F.SilkS")
		)
		(fp_line
			(start 0.7874 -0.4064)
			(end 0.7874 0.4064)
			(stroke
				(width 0.1524)
				(type default)
			)
			(layer "F.SilkS")
		)
		(fp_line
			(start -0.7874 0.4064)
			(end -0.7874 -0.4064)
			(stroke
				(width 0.1524)
				(type default)
			)
			(layer "F.SilkS")
		)
		(fp_line
			(start -0.7874 -0.4064)
			(end 0.7874 -0.4064)
			(stroke
				(width 0.1524)
				(type default)
			)
			(layer "F.SilkS")
		)
		(fp_line
			(start 0.67945 0.3048)
			(end 0.120396 0.3048)
			(stroke
				(width 0.1)
				(type default)
			)
			(layer "F.Fab")
		)
		(fp_line
			(start 0.67945 -0.3048)
			(end 0.67945 0.3048)
			(stroke
				(width 0.1)
				(type default)
			)
			(layer "F.Fab")
		)
		(fp_line
			(start 0.12065 -0.2794)
			(end 0.12065 -0.3048)
			(stroke
				(width 0.1)
				(type default)
			)
			(layer "F.Fab")
		)
		(fp_line
			(start 0.12065 -0.3048)
			(end 0.67945 -0.3048)
			(stroke
				(width 0.1)
				(type default)
			)
			(layer "F.Fab")
		)
		(fp_line
			(start 0.120396 0.3048)
			(end 0.120396 0.2794)
			(stroke
				(width 0.1)
				(type default)
			)
			(layer "F.Fab")
		)
		(fp_line
			(start 0.120396 0.2794)
			(end -0.12065 0.2794)
			(stroke
				(width 0.1)
				(type default)
			)
			(layer "F.Fab")
		)
		(fp_line
			(start -0.12065 0.3048)
			(end -0.67945 0.3048)
			(stroke
				(width 0.1)
				(type default)
			)
			(layer "F.Fab")
		)
		(fp_line
			(start -0.12065 0.2794)
			(end -0.12065 0.3048)
			(stroke
				(width 0.1)
				(type default)
			)
			(layer "F.Fab")
		)
		(fp_line
			(start -0.12065 -0.2794)
			(end 0.12065 -0.2794)
			(stroke
				(width 0.1)
				(type default)
			)
			(layer "F.Fab")
		)
		(fp_line
			(start -0.12065 -0.305054)
			(end -0.12065 -0.2794)
			(stroke
				(width 0.1)
				(type default)
			)
			(layer "F.Fab")
		)
		(fp_line
			(start -0.67945 0.3048)
			(end -0.67945 -0.305054)
			(stroke
				(width 0.1)
				(type default)
			)
			(layer "F.Fab")
		)
		(fp_line
			(start -0.67945 -0.305054)
			(end -0.12065 -0.305054)
			(stroke
				(width 0.1)
				(type default)
			)
			(layer "F.Fab")
		)
		(pad "1" smd circle
			(at -0.40005 0 180)
			(size 0 0)
			(layers "F.Cu" "F.Mask" "F.Paste")
			(net "HSC_EN")
		)
		(pad "2" smd circle
			(at 0.40005 0 180)
			(size 0 0)
			(layers "F.Cu" "F.Mask" "F.Paste")
			(net "AGND_HSC")
		)
	)
	(footprint ""
		(layer "F.Cu")
		(at 407.570432 -36.48837)
		(property "Reference" "SW5"
			(at -5.793232 4.106672 0)
			(unlocked yes)
			(layer "F.SilkS")
			(effects
				(font
					(size 0.7874 0.5842)
					(thickness 0.1524)
				)
				(justify left)
			)
		)
		(property "Value" ""
			(at 0 0 0)
			(layer "F.Fab")
			(effects
				(font
					(size 1.27 1.27)
				)
			)
		)
		(duplicate_pad_numbers_are_jumpers no)
		(fp_line
			(start -3.10007 -3.10007)
			(end -3.10007 3.10007)
			(stroke
				(width 0.1524)
				(type default)
			)
			(layer "F.SilkS")
		)
		(fp_line
			(start -3.10007 3.10007)
			(end -3.048 3.10007)
			(stroke
				(width 0.1524)
				(type default)
			)
			(layer "F.SilkS")
		)
		(fp_line
			(start -3.048 -3.10007)
			(end -3.10007 -3.10007)
			(stroke
				(width 0.1524)
				(type default)
			)
			(layer "F.SilkS")
		)
		(fp_line
			(start -1.4478 3.10007)
			(end 1.4478 3.10007)
			(stroke
				(width 0.1524)
				(type default)
			)
			(layer "F.SilkS")
		)
		(fp_line
			(start 1.4478 -3.10007)
			(end -1.4478 -3.10007)
			(stroke
				(width 0.1524)
				(type default)
			)
			(layer "F.SilkS")
		)
		(fp_line
			(start 3.048 3.10007)
			(end 3.10007 3.10007)
			(stroke
				(width 0.1524)
				(type default)
			)
			(layer "F.SilkS")
		)
		(fp_line
			(start 3.10007 -3.10007)
			(end 3.048 -3.10007)
			(stroke
				(width 0.1524)
				(type default)
			)
			(layer "F.SilkS")
		)
		(fp_line
			(start 3.10007 3.10007)
			(end 3.10007 -3.10007)
			(stroke
				(width 0.1524)
				(type default)
			)
			(layer "F.SilkS")
		)
		(fp_circle
			(center 0 0)
			(end 1.75006 0)
			(stroke
				(width 0.1524)
				(type default)
			)
			(fill no)
			(layer "F.SilkS")
		)
		(fp_poly
			(pts
				(xy 2.757932 -5.969) (xy 2.249932 -4.953) (xy 1.741932 -5.969)
			)
			(stroke
				(width 0)
				(type default)
			)
			(fill yes)
			(layer "F.SilkS")
		)
		(fp_line
			(start -3.10007 -3.10007)
			(end -3.10007 3.10007)
			(stroke
				(width 0.1)
				(type default)
			)
			(layer "F.Fab")
		)
		(fp_line
			(start -3.10007 3.10007)
			(end 3.10007 3.10007)
			(stroke
				(width 0.1)
				(type default)
			)
			(layer "F.Fab")
		)
		(fp_line
			(start 3.10007 -3.10007)
			(end -3.10007 -3.10007)
			(stroke
				(width 0.1)
				(type default)
			)
			(layer "F.Fab")
		)
		(fp_line
			(start 3.10007 3.10007)
			(end 3.10007 -3.10007)
			(stroke
				(width 0.1)
				(type default)
			)
			(layer "F.Fab")
		)
		(fp_poly
			(pts
				(xy 2.757932 -5.969) (xy 1.741932 -5.969) (xy 2.249932 -4.953)
			)
			(stroke
				(width 0)
				(type default)
			)
			(fill yes)
			(layer "F.Fab")
		)
		(pad "1" smd rect
			(at 2.249932 -3.9751)
			(size 1.3208 1.5494)
			(layers "F.Cu" "F.Mask" "F.Paste")
			(net "PD_RST_RTCRST_N")
		)
		(pad "2" smd rect
			(at 2.249932 3.9751)
			(size 1.3208 1.5494)
			(layers "F.Cu" "F.Mask" "F.Paste")
			(net "PD_RST_RTCRST_N")
		)
		(pad "3" smd rect
			(at -2.249932 -3.9751)
			(size 1.3208 1.5494)
			(layers "F.Cu" "F.Mask" "F.Paste")
			(net "RST_RTCRST_N")
		)
		(pad "4" smd rect
			(at -2.249932 3.9751)
			(size 1.3208 1.5494)
			(layers "F.Cu" "F.Mask" "F.Paste")
			(net "RST_RTCRST_N")
		)
	)
)
